(kicad_pcb
	(version 20260206)
	(generator "pcbnew")
	(generator_version "10.0")
	(general
		(thickness 1.6)
		(legacy_teardrops no)
	)
	(paper "A4")
	(title_block
		(title "03242023_DA0F0TMBIJ0_F0T_Motherboard_J_brd_V01_OCP.brd")
		(comment 1 "Grand Teton / footprints 1384-1391 of 6105")
	)
	(layers
		(0 "F.Cu" signal "TOP")
		(4 "In1.Cu" signal "GND")
		(6 "In2.Cu" signal "IN1")
		(8 "In3.Cu" signal "GND1")
		(10 "In4.Cu" signal "IN2")
		(12 "In5.Cu" signal "GND2")
		(14 "In6.Cu" signal "IN3")
		(16 "In7.Cu" signal "GND3")
		(18 "In8.Cu" signal "VCC")
		(20 "In9.Cu" signal "VCC1")
		(22 "In10.Cu" signal "GND4")
		(24 "In11.Cu" signal "IN4")
		(26 "In12.Cu" signal "GND5")
		(28 "In13.Cu" signal "IN5")
		(30 "In14.Cu" signal "GND6")
		(32 "In15.Cu" signal "IN6")
		(34 "In16.Cu" signal "GND7")
		(2 "B.Cu" signal "BOTTOM")
		(9 "F.Adhes" user "F.Adhesive")
		(11 "B.Adhes" user "B.Adhesive")
		(13 "F.Paste" user "Package Geometry/Pastemask Top")
		(15 "B.Paste" user "Package Geometry/Pastemask Bottom")
		(5 "F.SilkS" user "Ref Des/Silkscreen Top")
		(7 "B.SilkS" user "Ref Des/Silkscreen Bottom")
		(1 "F.Mask" user "Board Geometry/Soldermask Top")
		(3 "B.Mask" user "Board Geometry/Soldermask Bottom")
		(17 "Dwgs.User" user "User.Drawings")
		(19 "Cmts.User" user "User.Comments")
		(21 "Eco1.User" user "User.Eco1")
		(23 "Eco2.User" user "User.Eco2")
		(25 "Edge.Cuts" user "Board Geometry/Outline")
		(27 "Margin" user)
		(31 "F.CrtYd" user "Package Geometry/Place Bound Top")
		(29 "B.CrtYd" user "Package Geometry/Place Bound Bottom")
		(35 "F.Fab" user "Ref Des/Assembly Top")
		(33 "B.Fab" user "Ref Des/Assembly Bottom")
	)
	(footprint ""
		(layer "F.Cu")
		(at 118.09222 -296.05478 180)
		(property "Reference" "C245"
			(at 0 0 180)
			(layer "F.SilkS")
			(hide yes)
			(effects
				(font
					(size 1.27 1.27)
				)
			)
		)
		(property "Value" ""
			(at 0 0 180)
			(layer "F.Fab")
			(effects
				(font
					(size 1.27 1.27)
				)
			)
		)
		(duplicate_pad_numbers_are_jumpers no)
		(fp_line
			(start 1.524 0.762)
			(end -1.524 0.762)
			(stroke
				(width 0.1524)
				(type default)
			)
			(layer "F.SilkS")
		)
		(fp_line
			(start 1.524 -0.762)
			(end 1.524 0.762)
			(stroke
				(width 0.1524)
				(type default)
			)
			(layer "F.SilkS")
		)
		(fp_line
			(start -1.524 0.762)
			(end -1.524 -0.762)
			(stroke
				(width 0.1524)
				(type default)
			)
			(layer "F.SilkS")
		)
		(fp_line
			(start -1.524 -0.762)
			(end 1.524 -0.762)
			(stroke
				(width 0.1524)
				(type default)
			)
			(layer "F.SilkS")
		)
		(fp_line
			(start 1.1049 0.724916)
			(end 1.1049 -0.724916)
			(stroke
				(width 0.1)
				(type default)
			)
			(layer "F.Fab")
		)
		(fp_line
			(start 1.1049 -0.724916)
			(end -1.1049 -0.724916)
			(stroke
				(width 0.1)
				(type default)
			)
			(layer "F.Fab")
		)
		(fp_line
			(start -1.1049 0.724916)
			(end 1.1049 0.724916)
			(stroke
				(width 0.1)
				(type default)
			)
			(layer "F.Fab")
		)
		(fp_line
			(start -1.1049 -0.724916)
			(end -1.1049 0.724916)
			(stroke
				(width 0.1)
				(type default)
			)
			(layer "F.Fab")
		)
		(pad "1" smd rect
			(at -0.889 0)
			(size 1.016 1.27)
			(layers "F.Cu" "F.Mask" "F.Paste")
			(net "PVCCIN_CPU1")
		)
		(pad "2" smd rect
			(at 0.889 0)
			(size 1.016 1.27)
			(layers "F.Cu" "F.Mask" "F.Paste")
			(net "GND")
		)
	)
	(footprint ""
		(layer "F.Cu")
		(at 128.401572 -134.066026)
		(property "Reference" "R3580"
			(at 0 0 0)
			(layer "F.SilkS")
			(hide yes)
			(effects
				(font
					(size 1.27 1.27)
				)
			)
		)
		(property "Value" ""
			(at 0 0 0)
			(layer "F.Fab")
			(effects
				(font
					(size 1.27 1.27)
				)
			)
		)
		(duplicate_pad_numbers_are_jumpers no)
		(fp_line
			(start -0.7874 -0.4064)
			(end 0.7874 -0.4064)
			(stroke
				(width 0.1524)
				(type default)
			)
			(layer "F.SilkS")
		)
		(fp_line
			(start -0.7874 0.4064)
			(end -0.7874 -0.4064)
			(stroke
				(width 0.1524)
				(type default)
			)
			(layer "F.SilkS")
		)
		(fp_line
			(start 0.7874 -0.4064)
			(end 0.7874 0.4064)
			(stroke
				(width 0.1524)
				(type default)
			)
			(layer "F.SilkS")
		)
		(fp_line
			(start 0.7874 0.4064)
			(end -0.7874 0.4064)
			(stroke
				(width 0.1524)
				(type default)
			)
			(layer "F.SilkS")
		)
		(fp_line
			(start -0.67945 -0.305054)
			(end -0.12065 -0.305054)
			(stroke
				(width 0.1)
				(type default)
			)
			(layer "F.Fab")
		)
		(fp_line
			(start -0.67945 0.3048)
			(end -0.67945 -0.305054)
			(stroke
				(width 0.1)
				(type default)
			)
			(layer "F.Fab")
		)
		(fp_line
			(start -0.12065 -0.305054)
			(end -0.12065 -0.2794)
			(stroke
				(width 0.1)
				(type default)
			)
			(layer "F.Fab")
		)
		(fp_line
			(start -0.12065 -0.2794)
			(end 0.12065 -0.2794)
			(stroke
				(width 0.1)
				(type default)
			)
			(layer "F.Fab")
		)
		(fp_line
			(start -0.12065 0.2794)
			(end -0.12065 0.3048)
			(stroke
				(width 0.1)
				(type default)
			)
			(layer "F.Fab")
		)
		(fp_line
			(start -0.12065 0.3048)
			(end -0.67945 0.3048)
			(stroke
				(width 0.1)
				(type default)
			)
			(layer "F.Fab")
		)
		(fp_line
			(start 0.120396 0.2794)
			(end -0.12065 0.2794)
			(stroke
				(width 0.1)
				(type default)
			)
			(layer "F.Fab")
		)
		(fp_line
			(start 0.120396 0.3048)
			(end 0.120396 0.2794)
			(stroke
				(width 0.1)
				(type default)
			)
			(layer "F.Fab")
		)
		(fp_line
			(start 0.12065 -0.3048)
			(end 0.67945 -0.3048)
			(stroke
				(width 0.1)
				(type default)
			)
			(layer "F.Fab")
		)
		(fp_line
			(start 0.12065 -0.2794)
			(end 0.12065 -0.3048)
			(stroke
				(width 0.1)
				(type default)
			)
			(layer "F.Fab")
		)
		(fp_line
			(start 0.67945 -0.3048)
			(end 0.67945 0.3048)
			(stroke
				(width 0.1)
				(type default)
			)
			(layer "F.Fab")
		)
		(fp_line
			(start 0.67945 0.3048)
			(end 0.120396 0.3048)
			(stroke
				(width 0.1)
				(type default)
			)
			(layer "F.Fab")
		)
		(pad "1" smd circle
			(at -0.40005 0)
			(size 0 0)
			(layers "F.Cu" "F.Mask" "F.Paste")
			(net "SMB_INA230_3V3AUX_SCL_R")
		)
		(pad "2" smd circle
			(at 0.40005 0)
			(size 0 0)
			(layers "F.Cu" "F.Mask" "F.Paste")
			(net "SMB_INA230_3V3AUX_SCL")
		)
	)
	(footprint ""
		(layer "F.Cu")
		(at 180.528468 -44.091098 180)
		(property "Reference" "C1099"
			(at 0 0 180)
			(layer "F.SilkS")
			(hide yes)
			(effects
				(font
					(size 1.27 1.27)
				)
			)
		)
		(property "Value" ""
			(at 0 0 180)
			(layer "F.Fab")
			(effects
				(font
					(size 1.27 1.27)
				)
			)
		)
		(duplicate_pad_numbers_are_jumpers no)
		(fp_line
			(start 0.299974 0.150114)
			(end -0.299974 0.150114)
			(stroke
				(width 0.1)
				(type default)
			)
			(layer "F.Fab")
		)
		(fp_line
			(start 0.299974 -0.150114)
			(end 0.299974 0.150114)
			(stroke
				(width 0.1)
				(type default)
			)
			(layer "F.Fab")
		)
		(fp_line
			(start -0.299974 0.150114)
			(end -0.299974 -0.150114)
			(stroke
				(width 0.1)
				(type default)
			)
			(layer "F.Fab")
		)
		(fp_line
			(start -0.299974 -0.150114)
			(end 0.299974 -0.150114)
			(stroke
				(width 0.1)
				(type default)
			)
			(layer "F.Fab")
		)
		(pad "1" smd rect
			(at -0.2667 0 180)
			(size 0.3048 0.381)
			(layers "F.Cu" "F.Mask" "F.Paste")
			(net "P3E_PCH_M2_TX_DN<3>")
		)
		(pad "2" smd rect
			(at 0.2667 0 180)
			(size 0.3048 0.381)
			(layers "F.Cu" "F.Mask" "F.Paste")
			(net "P3E_PCH_M2_TX_C_DN<3>")
		)
		(zone
			(layer "In1.Cu")
			(hatch none 0.5)
			(connect_pads
				(clearance 0)
			)
			(min_thickness 0.25)
			(keepout
				(tracks not_allowed)
				(vias allowed)
				(pads allowed)
				(copperpour not_allowed)
				(footprints allowed)
			)
			(placement
				(enabled no)
				(sheetname "")
			)
			(fill
				(thermal_gap 0.5)
				(thermal_bridge_width 0.5)
				(island_removal_mode 0)
			)
			(polygon
				(pts
					(arc
						(start 180.388768 -44.332398)
						(mid 180.44265 -44.31008)
						(end 180.464968 -44.256198)
					)
					(arc
						(start 180.464968 -43.925998)
						(mid 180.44265 -43.872116)
						(end 180.388768 -43.849798)
					)
					(arc
						(start 180.134768 -43.849798)
						(mid 180.080886 -43.872116)
						(end 180.058568 -43.925998)
					)
					(arc
						(start 180.058568 -44.256198)
						(mid 180.080886 -44.31008)
						(end 180.134768 -44.332398)
					)
				)
			)
		)
		(zone
			(layer "In1.Cu")
			(hatch none 0.5)
			(connect_pads
				(clearance 0)
			)
			(min_thickness 0.25)
			(keepout
				(tracks not_allowed)
				(vias allowed)
				(pads allowed)
				(copperpour not_allowed)
				(footprints allowed)
			)
			(placement
				(enabled no)
				(sheetname "")
			)
			(fill
				(thermal_gap 0.5)
				(thermal_bridge_width 0.5)
				(island_removal_mode 0)
			)
			(polygon
				(pts
					(arc
						(start 180.922168 -44.332398)
						(mid 180.97605 -44.31008)
						(end 180.998368 -44.256198)
					)
					(arc
						(start 180.998368 -43.925998)
						(mid 180.97605 -43.872116)
						(end 180.922168 -43.849798)
					)
					(arc
						(start 180.668168 -43.849798)
						(mid 180.614286 -43.872116)
						(end 180.591968 -43.925998)
					)
					(arc
						(start 180.591968 -44.256198)
						(mid 180.614286 -44.31008)
						(end 180.668168 -44.332398)
					)
				)
			)
		)
	)
	(footprint ""
		(layer "F.Cu")
		(at 309.030624 -62.375542 90)
		(property "Reference" "R3064"
			(at 0 0 90)
			(layer "F.SilkS")
			(hide yes)
			(effects
				(font
					(size 1.27 1.27)
				)
			)
		)
		(property "Value" ""
			(at 0 0 90)
			(layer "F.Fab")
			(effects
				(font
					(size 1.27 1.27)
				)
			)
		)
		(duplicate_pad_numbers_are_jumpers no)
		(fp_line
			(start 0.7874 -0.4064)
			(end 0.7874 0.4064)
			(stroke
				(width 0.1524)
				(type default)
			)
			(layer "F.SilkS")
		)
		(fp_line
			(start -0.7874 -0.4064)
			(end 0.7874 -0.4064)
			(stroke
				(width 0.1524)
				(type default)
			)
			(layer "F.SilkS")
		)
		(fp_line
			(start 0.7874 0.4064)
			(end -0.7874 0.4064)
			(stroke
				(width 0.1524)
				(type default)
			)
			(layer "F.SilkS")
		)
		(fp_line
			(start -0.7874 0.4064)
			(end -0.7874 -0.4064)
			(stroke
				(width 0.1524)
				(type default)
			)
			(layer "F.SilkS")
		)
		(fp_line
			(start -0.12065 -0.305054)
			(end -0.12065 -0.2794)
			(stroke
				(width 0.1)
				(type default)
			)
			(layer "F.Fab")
		)
		(fp_line
			(start -0.67945 -0.305054)
			(end -0.12065 -0.305054)
			(stroke
				(width 0.1)
				(type default)
			)
			(layer "F.Fab")
		)
		(fp_line
			(start 0.67945 -0.3048)
			(end 0.67945 0.3048)
			(stroke
				(width 0.1)
				(type default)
			)
			(layer "F.Fab")
		)
		(fp_line
			(start 0.12065 -0.3048)
			(end 0.67945 -0.3048)
			(stroke
				(width 0.1)
				(type default)
			)
			(layer "F.Fab")
		)
		(fp_line
			(start 0.12065 -0.2794)
			(end 0.12065 -0.3048)
			(stroke
				(width 0.1)
				(type default)
			)
			(layer "F.Fab")
		)
		(fp_line
			(start -0.12065 -0.2794)
			(end 0.12065 -0.2794)
			(stroke
				(width 0.1)
				(type default)
			)
			(layer "F.Fab")
		)
		(fp_line
			(start 0.120396 0.2794)
			(end -0.12065 0.2794)
			(stroke
				(width 0.1)
				(type default)
			)
			(layer "F.Fab")
		)
		(fp_line
			(start -0.12065 0.2794)
			(end -0.12065 0.3048)
			(stroke
				(width 0.1)
				(type default)
			)
			(layer "F.Fab")
		)
		(fp_line
			(start 0.67945 0.3048)
			(end 0.120396 0.3048)
			(stroke
				(width 0.1)
				(type default)
			)
			(layer "F.Fab")
		)
		(fp_line
			(start 0.120396 0.3048)
			(end 0.120396 0.2794)
			(stroke
				(width 0.1)
				(type default)
			)
			(layer "F.Fab")
		)
		(fp_line
			(start -0.12065 0.3048)
			(end -0.67945 0.3048)
			(stroke
				(width 0.1)
				(type default)
			)
			(layer "F.Fab")
		)
		(fp_line
			(start -0.67945 0.3048)
			(end -0.67945 -0.305054)
			(stroke
				(width 0.1)
				(type default)
			)
			(layer "F.Fab")
		)
		(pad "1" smd circle
			(at -0.40005 0 90)
			(size 0 0)
			(layers "F.Cu" "F.Mask" "F.Paste")
			(net "PECI_CPU_GTL")
		)
		(pad "2" smd circle
			(at 0.40005 0 90)
			(size 0 0)
			(layers "F.Cu" "F.Mask" "F.Paste")
			(net "PECI_BMC_ME")
		)
	)
	(footprint ""
		(layer "F.Cu")
		(at 111.332772 -130.869182)
		(property "Reference" "R1090"
			(at 0 0 0)
			(layer "F.SilkS")
			(hide yes)
			(effects
				(font
					(size 1.27 1.27)
				)
			)
		)
		(property "Value" ""
			(at 0 0 0)
			(layer "F.Fab")
			(effects
				(font
					(size 1.27 1.27)
				)
			)
		)
		(duplicate_pad_numbers_are_jumpers no)
		(fp_line
			(start -0.7874 -0.4064)
			(end 0.7874 -0.4064)
			(stroke
				(width 0.1524)
				(type default)
			)
			(layer "F.SilkS")
		)
		(fp_line
			(start -0.7874 0.4064)
			(end -0.7874 -0.4064)
			(stroke
				(width 0.1524)
				(type default)
			)
			(layer "F.SilkS")
		)
		(fp_line
			(start 0.7874 -0.4064)
			(end 0.7874 0.4064)
			(stroke
				(width 0.1524)
				(type default)
			)
			(layer "F.SilkS")
		)
		(fp_line
			(start 0.7874 0.4064)
			(end -0.7874 0.4064)
			(stroke
				(width 0.1524)
				(type default)
			)
			(layer "F.SilkS")
		)
		(fp_line
			(start -0.67945 -0.305054)
			(end -0.12065 -0.305054)
			(stroke
				(width 0.1)
				(type default)
			)
			(layer "F.Fab")
		)
		(fp_line
			(start -0.67945 0.3048)
			(end -0.67945 -0.305054)
			(stroke
				(width 0.1)
				(type default)
			)
			(layer "F.Fab")
		)
		(fp_line
			(start -0.12065 -0.305054)
			(end -0.12065 -0.2794)
			(stroke
				(width 0.1)
				(type default)
			)
			(layer "F.Fab")
		)
		(fp_line
			(start -0.12065 -0.2794)
			(end 0.12065 -0.2794)
			(stroke
				(width 0.1)
				(type default)
			)
			(layer "F.Fab")
		)
		(fp_line
			(start -0.12065 0.2794)
			(end -0.12065 0.3048)
			(stroke
				(width 0.1)
				(type default)
			)
			(layer "F.Fab")
		)
		(fp_line
			(start -0.12065 0.3048)
			(end -0.67945 0.3048)
			(stroke
				(width 0.1)
				(type default)
			)
			(layer "F.Fab")
		)
		(fp_line
			(start 0.120396 0.2794)
			(end -0.12065 0.2794)
			(stroke
				(width 0.1)
				(type default)
			)
			(layer "F.Fab")
		)
		(fp_line
			(start 0.120396 0.3048)
			(end 0.120396 0.2794)
			(stroke
				(width 0.1)
				(type default)
			)
			(layer "F.Fab")
		)
		(fp_line
			(start 0.12065 -0.3048)
			(end 0.67945 -0.3048)
			(stroke
				(width 0.1)
				(type default)
			)
			(layer "F.Fab")
		)
		(fp_line
			(start 0.12065 -0.2794)
			(end 0.12065 -0.3048)
			(stroke
				(width 0.1)
				(type default)
			)
			(layer "F.Fab")
		)
		(fp_line
			(start 0.67945 -0.3048)
			(end 0.67945 0.3048)
			(stroke
				(width 0.1)
				(type default)
			)
			(layer "F.Fab")
		)
		(fp_line
			(start 0.67945 0.3048)
			(end 0.120396 0.3048)
			(stroke
				(width 0.1)
				(type default)
			)
			(layer "F.Fab")
		)
		(pad "1" smd circle
			(at -0.40005 0)
			(size 0 0)
			(layers "F.Cu" "F.Mask" "F.Paste")
			(net "P3V3_AUX")
		)
		(pad "2" smd circle
			(at 0.40005 0)
			(size 0 0)
			(layers "F.Cu" "F.Mask" "F.Paste")
			(net "SMB_SENSOR_M2_P0_3V3AUX_SDA")
		)
	)
	(footprint ""
		(layer "F.Cu")
		(at 461.720946 -102.41915)
		(property "Reference" "R1147"
			(at 0 0 0)
			(layer "F.SilkS")
			(hide yes)
			(effects
				(font
					(size 1.27 1.27)
				)
			)
		)
		(property "Value" ""
			(at 0 0 0)
			(layer "F.Fab")
			(effects
				(font
					(size 1.27 1.27)
				)
			)
		)
		(duplicate_pad_numbers_are_jumpers no)
		(fp_line
			(start -0.7874 -0.4064)
			(end 0.7874 -0.4064)
			(stroke
				(width 0.1524)
				(type default)
			)
			(layer "F.SilkS")
		)
		(fp_line
			(start -0.7874 0.4064)
			(end -0.7874 -0.4064)
			(stroke
				(width 0.1524)
				(type default)
			)
			(layer "F.SilkS")
		)
		(fp_line
			(start 0.7874 -0.4064)
			(end 0.7874 0.4064)
			(stroke
				(width 0.1524)
				(type default)
			)
			(layer "F.SilkS")
		)
		(fp_line
			(start 0.7874 0.4064)
			(end -0.7874 0.4064)
			(stroke
				(width 0.1524)
				(type default)
			)
			(layer "F.SilkS")
		)
		(fp_line
			(start -0.67945 -0.305054)
			(end -0.12065 -0.305054)
			(stroke
				(width 0.1)
				(type default)
			)
			(layer "F.Fab")
		)
		(fp_line
			(start -0.67945 0.3048)
			(end -0.67945 -0.305054)
			(stroke
				(width 0.1)
				(type default)
			)
			(layer "F.Fab")
		)
		(fp_line
			(start -0.12065 -0.305054)
			(end -0.12065 -0.2794)
			(stroke
				(width 0.1)
				(type default)
			)
			(layer "F.Fab")
		)
		(fp_line
			(start -0.12065 -0.2794)
			(end 0.12065 -0.2794)
			(stroke
				(width 0.1)
				(type default)
			)
			(layer "F.Fab")
		)
		(fp_line
			(start -0.12065 0.2794)
			(end -0.12065 0.3048)
			(stroke
				(width 0.1)
				(type default)
			)
			(layer "F.Fab")
		)
		(fp_line
			(start -0.12065 0.3048)
			(end -0.67945 0.3048)
			(stroke
				(width 0.1)
				(type default)
			)
			(layer "F.Fab")
		)
		(fp_line
			(start 0.120396 0.2794)
			(end -0.12065 0.2794)
			(stroke
				(width 0.1)
				(type default)
			)
			(layer "F.Fab")
		)
		(fp_line
			(start 0.120396 0.3048)
			(end 0.120396 0.2794)
			(stroke
				(width 0.1)
				(type default)
			)
			(layer "F.Fab")
		)
		(fp_line
			(start 0.12065 -0.3048)
			(end 0.67945 -0.3048)
			(stroke
				(width 0.1)
				(type default)
			)
			(layer "F.Fab")
		)
		(fp_line
			(start 0.12065 -0.2794)
			(end 0.12065 -0.3048)
			(stroke
				(width 0.1)
				(type default)
			)
			(layer "F.Fab")
		)
		(fp_line
			(start 0.67945 -0.3048)
			(end 0.67945 0.3048)
			(stroke
				(width 0.1)
				(type default)
			)
			(layer "F.Fab")
		)
		(fp_line
			(start 0.67945 0.3048)
			(end 0.120396 0.3048)
			(stroke
				(width 0.1)
				(type default)
			)
			(layer "F.Fab")
		)
		(pad "1" smd circle
			(at -0.40005 0)
			(size 0 0)
			(layers "F.Cu" "F.Mask" "F.Paste")
			(net "HP_LVC3_OCP_V3_1_PRSNT2_N_R")
		)
		(pad "2" smd circle
			(at 0.40005 0)
			(size 0 0)
			(layers "F.Cu" "F.Mask" "F.Paste")
			(net "HP_LVC3_OCP_V3_1_ATTN_OUT_SW_N")
		)
	)
	(footprint ""
		(layer "F.Cu")
		(at 461.459834 -347.699838)
		(property "Reference" "H98"
			(at -6.703314 -4.139692 0)
			(unlocked yes)
			(layer "F.SilkS")
			(effects
				(font
					(size 0.7874 0.5842)
					(thickness 0.1524)
				)
				(justify left)
			)
		)
		(property "Value" ""
			(at 0 0 0)
			(layer "F.Fab")
			(effects
				(font
					(size 1.27 1.27)
				)
			)
		)
		(duplicate_pad_numbers_are_jumpers no)
		(pad "1" thru_hole circle
			(at 0 0)
			(size 10.0076 10.0076)
			(drill 5.6134)
			(layers "*.Cu" "*.Mask")
			(remove_unused_layers no)
			(net "GND")
			(clearance -1.9431)
		)
	)
	(footprint ""
		(layer "F.Cu")
		(at 18.302478 -17.623536 90)
		(property "Reference" "C808"
			(at 0 0 90)
			(layer "F.SilkS")
			(hide yes)
			(effects
				(font
					(size 1.27 1.27)
				)
			)
		)
		(property "Value" ""
			(at 0 0 90)
			(layer "F.Fab")
			(effects
				(font
					(size 1.27 1.27)
				)
			)
		)
		(duplicate_pad_numbers_are_jumpers no)
		(fp_line
			(start 0.299974 -0.150114)
			(end 0.299974 0.150114)
			(stroke
				(width 0.1)
				(type default)
			)
			(layer "F.Fab")
		)
		(fp_line
			(start -0.299974 -0.150114)
			(end 0.299974 -0.150114)
			(stroke
				(width 0.1)
				(type default)
			)
			(layer "F.Fab")
		)
		(fp_line
			(start 0.299974 0.150114)
			(end -0.299974 0.150114)
			(stroke
				(width 0.1)
				(type default)
			)
			(layer "F.Fab")
		)
		(fp_line
			(start -0.299974 0.150114)
			(end -0.299974 -0.150114)
			(stroke
				(width 0.1)
				(type default)
			)
			(layer "F.Fab")
		)
		(pad "1" smd rect
			(at -0.2667 0 90)
			(size 0.3048 0.381)
			(layers "F.Cu" "F.Mask" "F.Paste")
			(net "P5E_CPU1_PE1_TX_C_DN<14>")
		)
		(pad "2" smd rect
			(at 0.2667 0 90)
			(size 0.3048 0.381)
			(layers "F.Cu" "F.Mask" "F.Paste")
			(net "P5E_CPU1_PE1_TX_DN<14>")
		)
	)
)
